# T6G (Grand Teton) — schematic netlist excerpt (pin names and nets, part order shuffled) for the footprints in the layout excerpt that follows; sources: Cadence DE-HDL packaged netlist, KiCad conversion of 04192023_DAF0TMB3IC0_F0TG_MB_C_brd_V02_OCP.brd

R1793  Q_RES  0 5% EMPTY  pkg 0402LF  page 257 : A = SMB_SCM_2_R4_SCL ; B = SMB_SEN_MAM_3V3AUX_SCL
C703  Q_CAP_DIFFBUS  DIFF BUS_0.22UF 6.3V 20% X6S  pkg C0201  page 67 : \1\ = P5E_CPU1_G1_TX_C_DP<3> ; \2\ = P5E_CPU1_G1_TX_DP<3>
R2588  Q_RES  22 1% CHIP  pkg 0402LF  page 262 : A = HSC_FAULT ; B = IRQ_HSC_FAULT_N

(kicad_pcb
	(version 20260206)
	(generator "pcbnew")
	(generator_version "10.0")
	(general
		(thickness 1.6)
		(legacy_teardrops no)
	)
	(paper "A4")
	(title_block
		(title "04192023_DAF0TMB3IC0_F0TG_MB_C_brd_V02_OCP.brd")
		(comment 1 "Grand Teton / footprints 2327-2329 of 8354")
	)
	(layers
		(0 "F.Cu" signal "TOP")
		(4 "In1.Cu" signal "GND")
		(6 "In2.Cu" signal "IN1")
		(8 "In3.Cu" signal "GND1")
		(10 "In4.Cu" signal "IN2")
		(12 "In5.Cu" signal "GND2")
		(14 "In6.Cu" signal "IN3")
		(16 "In7.Cu" signal "GND3")
		(18 "In8.Cu" signal "VCC")
		(20 "In9.Cu" signal "VCC1")
		(22 "In10.Cu" signal "GND4")
		(24 "In11.Cu" signal "IN4")
		(26 "In12.Cu" signal "GND5")
		(28 "In13.Cu" signal "IN5")
		(30 "In14.Cu" signal "GND6")
		(32 "In15.Cu" signal "IN6")
		(34 "In16.Cu" signal "GND7")
		(2 "B.Cu" signal "BOTTOM")
		(9 "F.Adhes" user "F.Adhesive")
		(11 "B.Adhes" user "B.Adhesive")
		(13 "F.Paste" user "Package Geometry/Pastemask Top")
		(15 "B.Paste" user "Package Geometry/Pastemask Bottom")
		(5 "F.SilkS" user "Ref Des/Silkscreen Top")
		(7 "B.SilkS" user "Ref Des/Silkscreen Bottom")
		(1 "F.Mask" user "Board Geometry/Soldermask Top")
		(3 "B.Mask" user "Board Geometry/Soldermask Bottom")
		(17 "Dwgs.User" user "User.Drawings")
		(19 "Cmts.User" user "User.Comments")
		(21 "Eco1.User" user "User.Eco1")
		(23 "Eco2.User" user "User.Eco2")
		(25 "Edge.Cuts" user "Board Geometry/Outline")
		(27 "Margin" user)
		(31 "F.CrtYd" user "Package Geometry/Place Bound Top")
		(29 "B.CrtYd" user "Package Geometry/Place Bound Bottom")
		(35 "F.Fab" user "Ref Des/Assembly Top")
		(33 "B.Fab" user "Ref Des/Assembly Bottom")
	)
	(footprint ""
		(layer "F.Cu")
		(at 329.360022 -34.985706 180)
		(property "Reference" "R1793"
			(at 0 0 180)
			(layer "F.SilkS")
			(hide yes)
			(effects
				(font
					(size 1.27 1.27)
				)
			)
		)
		(property "Value" ""
			(at 0 0 180)
			(layer "F.Fab")
			(effects
				(font
					(size 1.27 1.27)
				)
			)
		)
		(duplicate_pad_numbers_are_jumpers no)
		(fp_line
			(start 0.7874 0.4064)
			(end -0.7874 0.4064)
			(stroke
				(width 0.1524)
				(type default)
			)
			(layer "F.SilkS")
		)
		(fp_line
			(start 0.7874 -0.4064)
			(end 0.7874 0.4064)
			(stroke
				(width 0.1524)
				(type default)
			)
			(layer "F.SilkS")
		)
		(fp_line
			(start -0.7874 0.4064)
			(end -0.7874 -0.4064)
			(stroke
				(width 0.1524)
				(type default)
			)
			(layer "F.SilkS")
		)
		(fp_line
			(start -0.7874 -0.4064)
			(end 0.7874 -0.4064)
			(stroke
				(width 0.1524)
				(type default)
			)
			(layer "F.SilkS")
		)
		(fp_line
			(start 0.67945 0.3048)
			(end 0.120396 0.3048)
			(stroke
				(width 0.1)
				(type default)
			)
			(layer "F.Fab")
		)
		(fp_line
			(start 0.67945 -0.3048)
			(end 0.67945 0.3048)
			(stroke
				(width 0.1)
				(type default)
			)
			(layer "F.Fab")
		)
		(fp_line
			(start 0.12065 -0.2794)
			(end 0.12065 -0.3048)
			(stroke
				(width 0.1)
				(type default)
			)
			(layer "F.Fab")
		)
		(fp_line
			(start 0.12065 -0.3048)
			(end 0.67945 -0.3048)
			(stroke
				(width 0.1)
				(type default)
			)
			(layer "F.Fab")
		)
		(fp_line
			(start 0.120396 0.3048)
			(end 0.120396 0.2794)
			(stroke
				(width 0.1)
				(type default)
			)
			(layer "F.Fab")
		)
		(fp_line
			(start 0.120396 0.2794)
			(end -0.12065 0.2794)
			(stroke
				(width 0.1)
				(type default)
			)
			(layer "F.Fab")
		)
		(fp_line
			(start -0.12065 0.3048)
			(end -0.67945 0.3048)
			(stroke
				(width 0.1)
				(type default)
			)
			(layer "F.Fab")
		)
		(fp_line
			(start -0.12065 0.2794)
			(end -0.12065 0.3048)
			(stroke
				(width 0.1)
				(type default)
			)
			(layer "F.Fab")
		)
		(fp_line
			(start -0.12065 -0.2794)
			(end 0.12065 -0.2794)
			(stroke
				(width 0.1)
				(type default)
			)
			(layer "F.Fab")
		)
		(fp_line
			(start -0.12065 -0.305054)
			(end -0.12065 -0.2794)
			(stroke
				(width 0.1)
				(type default)
			)
			(layer "F.Fab")
		)
		(fp_line
			(start -0.67945 0.3048)
			(end -0.67945 -0.305054)
			(stroke
				(width 0.1)
				(type default)
			)
			(layer "F.Fab")
		)
		(fp_line
			(start -0.67945 -0.305054)
			(end -0.12065 -0.305054)
			(stroke
				(width 0.1)
				(type default)
			)
			(layer "F.Fab")
		)
		(pad "1" smd circle
			(at -0.40005 0 180)
			(size 0 0)
			(layers "F.Cu" "F.Mask" "F.Paste")
			(net "SMB_SCM_2_R4_SCL")
		)
		(pad "2" smd circle
			(at 0.40005 0 180)
			(size 0 0)
			(layers "F.Cu" "F.Mask" "F.Paste")
			(net "SMB_SEN_MAM_3V3AUX_SCL")
		)
	)
	(footprint ""
		(layer "F.Cu")
		(at 50.256694 -16.099536 90)
		(property "Reference" "C703"
			(at 0 0 90)
			(layer "F.SilkS")
			(hide yes)
			(effects
				(font
					(size 1.27 1.27)
				)
			)
		)
		(property "Value" ""
			(at 0 0 90)
			(layer "F.Fab")
			(effects
				(font
					(size 1.27 1.27)
				)
			)
		)
		(duplicate_pad_numbers_are_jumpers no)
		(fp_line
			(start 0.299974 -0.150114)
			(end 0.299974 0.150114)
			(stroke
				(width 0.1)
				(type default)
			)
			(layer "F.Fab")
		)
		(fp_line
			(start -0.299974 -0.150114)
			(end 0.299974 -0.150114)
			(stroke
				(width 0.1)
				(type default)
			)
			(layer "F.Fab")
		)
		(fp_line
			(start 0.299974 0.150114)
			(end -0.299974 0.150114)
			(stroke
				(width 0.1)
				(type default)
			)
			(layer "F.Fab")
		)
		(fp_line
			(start -0.299974 0.150114)
			(end -0.299974 -0.150114)
			(stroke
				(width 0.1)
				(type default)
			)
			(layer "F.Fab")
		)
		(pad "1" smd rect
			(at -0.2667 0 90)
			(size 0.3048 0.381)
			(layers "F.Cu" "F.Mask" "F.Paste")
			(net "P5E_CPU1_G1_TX_C_DP<3>")
		)
		(pad "2" smd rect
			(at 0.2667 0 90)
			(size 0.3048 0.381)
			(layers "F.Cu" "F.Mask" "F.Paste")
			(net "P5E_CPU1_G1_TX_DP<3>")
		)
	)
	(footprint ""
		(layer "F.Cu")
		(at 191.41694 -402.341842)
		(property "Reference" "R2588"
			(at 0 0 0)
			(layer "F.SilkS")
			(hide yes)
			(effects
				(font
					(size 1.27 1.27)
				)
			)
		)
		(property "Value" ""
			(at 0 0 0)
			(layer "F.Fab")
			(effects
				(font
					(size 1.27 1.27)
				)
			)
		)
		(duplicate_pad_numbers_are_jumpers no)
		(fp_line
			(start -0.7874 -0.4064)
			(end 0.7874 -0.4064)
			(stroke
				(width 0.1524)
				(type default)
			)
			(layer "F.SilkS")
		)
		(fp_line
			(start -0.7874 0.4064)
			(end -0.7874 -0.4064)
			(stroke
				(width 0.1524)
				(type default)
			)
			(layer "F.SilkS")
		)
		(fp_line
			(start 0.7874 -0.4064)
			(end 0.7874 0.4064)
			(stroke
				(width 0.1524)
				(type default)
			)
			(layer "F.SilkS")
		)
		(fp_line
			(start 0.7874 0.4064)
			(end -0.7874 0.4064)
			(stroke
				(width 0.1524)
				(type default)
			)
			(layer "F.SilkS")
		)
		(fp_line
			(start -0.67945 -0.305054)
			(end -0.12065 -0.305054)
			(stroke
				(width 0.1)
				(type default)
			)
			(layer "F.Fab")
		)
		(fp_line
			(start -0.67945 0.3048)
			(end -0.67945 -0.305054)
			(stroke
				(width 0.1)
				(type default)
			)
			(layer "F.Fab")
		)
		(fp_line
			(start -0.12065 -0.305054)
			(end -0.12065 -0.2794)
			(stroke
				(width 0.1)
				(type default)
			)
			(layer "F.Fab")
		)
		(fp_line
			(start -0.12065 -0.2794)
			(end 0.12065 -0.2794)
			(stroke
				(width 0.1)
				(type default)
			)
			(layer "F.Fab")
		)
		(fp_line
			(start -0.12065 0.2794)
			(end -0.12065 0.3048)
			(stroke
				(width 0.1)
				(type default)
			)
			(layer "F.Fab")
		)
		(fp_line
			(start -0.12065 0.3048)
			(end -0.67945 0.3048)
			(stroke
				(width 0.1)
				(type default)
			)
			(layer "F.Fab")
		)
		(fp_line
			(start 0.120396 0.2794)
			(end -0.12065 0.2794)
			(stroke
				(width 0.1)
				(type default)
			)
			(layer "F.Fab")
		)
		(fp_line
			(start 0.120396 0.3048)
			(end 0.120396 0.2794)
			(stroke
				(width 0.1)
				(type default)
			)
			(layer "F.Fab")
		)
		(fp_line
			(start 0.12065 -0.3048)
			(end 0.67945 -0.3048)
			(stroke
				(width 0.1)
				(type default)
			)
			(layer "F.Fab")
		)
		(fp_line
			(start 0.12065 -0.2794)
			(end 0.12065 -0.3048)
			(stroke
				(width 0.1)
				(type default)
			)
			(layer "F.Fab")
		)
		(fp_line
			(start 0.67945 -0.3048)
			(end 0.67945 0.3048)
			(stroke
				(width 0.1)
				(type default)
			)
			(layer "F.Fab")
		)
		(fp_line
			(start 0.67945 0.3048)
			(end 0.120396 0.3048)
			(stroke
				(width 0.1)
				(type default)
			)
			(layer "F.Fab")
		)
		(pad "1" smd circle
			(at -0.40005 0)
			(size 0 0)
			(layers "F.Cu" "F.Mask" "F.Paste")
			(net "HSC_FAULT")
		)
		(pad "2" smd circle
			(at 0.40005 0)
			(size 0 0)
			(layers "F.Cu" "F.Mask" "F.Paste")
			(net "IRQ_HSC_FAULT_N")
		)
	)
)
